(kicad_pcb
	(version 20260206)
	(generator "pcbnew")
	(generator_version "10.0")
	(general
		(thickness 1.6)
		(legacy_teardrops no)
	)
	(paper "A4")
	(title_block
		(title "baseboard — 13948-1b.1110WZS1818.brd")
		(comment 1 "Honey Badger (Wiwynn) / footprints 2345-2353 of 2523")
	)
	(layers
		(0 "F.Cu" signal "TOP")
		(4 "In1.Cu" signal "L2GND")
		(6 "In2.Cu" signal "L3")
		(8 "In3.Cu" signal "L4VCC")
		(10 "In4.Cu" signal "L5VCC")
		(12 "In5.Cu" signal "L6")
		(14 "In6.Cu" signal "L7GND")
		(2 "B.Cu" signal "BOTTOM")
		(9 "F.Adhes" user "F.Adhesive")
		(11 "B.Adhes" user "B.Adhesive")
		(13 "F.Paste" user "Package Geometry/Pastemask Top")
		(15 "B.Paste" user "Package Geometry/Pastemask Bottom")
		(5 "F.SilkS" user "Ref Des/Silkscreen Top")
		(7 "B.SilkS" user "Ref Des/Silkscreen Bottom")
		(1 "F.Mask" user "Board Geometry/Soldermask Top")
		(3 "B.Mask" user "Board Geometry/Soldermask Bottom")
		(17 "Dwgs.User" user "User.Drawings")
		(19 "Cmts.User" user "User.Comments")
		(21 "Eco1.User" user "User.Eco1")
		(23 "Eco2.User" user "User.Eco2")
		(25 "Edge.Cuts" user "Board Geometry/Outline")
		(27 "Margin" user)
		(31 "F.CrtYd" user "Package Geometry/Place Bound Top")
		(29 "B.CrtYd" user "Package Geometry/Place Bound Bottom")
		(35 "F.Fab" user "Ref Des/Assembly Top")
		(33 "B.Fab" user "Ref Des/Assembly Bottom")
	)
	(footprint ""
		(layer "B.Cu")
		(at 105.264966 -44.958 90)
		(property "Reference" "SC1033"
			(at 0 0 90)
			(layer "B.SilkS")
			(hide yes)
			(effects
				(font
					(size 1.27 1.27)
				)
				(justify mirror)
			)
		)
		(property "Value" "SC1KP50V2KX-1GP"
			(at -1.1811 -2.7051 90)
			(unlocked yes)
			(layer "B.Fab")
			(hide yes)
			(effects
				(font
					(size 1.016 1.016)
					(thickness 0.1524)
				)
				(justify mirror)
			)
		)
		(property "Device Type" "C402H22"
			(at -1.1811 -4.2291 90)
			(unlocked yes)
			(layer "B.Fab")
			(hide yes)
			(effects
				(font
					(size 1.016 1.016)
					(thickness 0.1524)
				)
				(justify mirror)
			)
		)
		(duplicate_pad_numbers_are_jumpers no)
		(fp_rect
			(start 0.4318 0.9525)
			(end -0.4318 -0.9525)
			(stroke
				(width 0)
				(type default)
			)
			(fill no)
			(layer "B.CrtYd")
		)
		(fp_rect
			(start 0.4318 0.9525)
			(end -0.4318 -0.9525)
			(stroke
				(width 0)
				(type default)
			)
			(fill no)
			(layer "B.Fab")
		)
		(pad "1" smd custom
			(at 0 -0.4445 270)
			(size 0.1524 0.1524)
			(layers "B.Cu" "B.Mask" "B.Paste")
			(net "P0V955_C")
			(options
				(clearance outline)
				(anchor circle)
			)
			(primitives
				(gr_poly
					(pts
						(arc
							(start 0.3048 0.2032)
							(mid 0.275042 0.275042)
							(end 0.2032 0.3048)
						)
						(arc
							(start -0.2032 0.3048)
							(mid -0.275042 0.275042)
							(end -0.3048 0.2032)
						)
						(arc
							(start -0.3048 -0.2032)
							(mid -0.275042 -0.275042)
							(end -0.2032 -0.3048)
						)
						(arc
							(start 0.2032 -0.3048)
							(mid 0.275042 -0.275042)
							(end 0.3048 -0.2032)
						)
					)
					(width 0)
					(fill yes)
				)
			)
		)
		(pad "2" smd custom
			(at 0 0.4445 270)
			(size 0.1524 0.1524)
			(layers "B.Cu" "B.Mask" "B.Paste")
			(net "GND")
			(options
				(clearance outline)
				(anchor circle)
			)
			(primitives
				(gr_poly
					(pts
						(arc
							(start 0.3048 0.2032)
							(mid 0.275042 0.275042)
							(end 0.2032 0.3048)
						)
						(arc
							(start -0.2032 0.3048)
							(mid -0.275042 0.275042)
							(end -0.3048 0.2032)
						)
						(arc
							(start -0.3048 -0.2032)
							(mid -0.275042 -0.275042)
							(end -0.2032 -0.3048)
						)
						(arc
							(start 0.2032 -0.3048)
							(mid 0.275042 -0.275042)
							(end 0.3048 -0.2032)
						)
					)
					(width 0)
					(fill yes)
				)
			)
		)
	)
	(footprint ""
		(layer "B.Cu")
		(at 118.37797 -94.615 90)
		(property "Reference" "SC1217"
			(at 0 0 90)
			(layer "B.SilkS")
			(hide yes)
			(effects
				(font
					(size 1.27 1.27)
				)
				(justify mirror)
			)
		)
		(property "Value" "SC1KP50V2KX-1GP"
			(at -1.1811 -2.7051 90)
			(unlocked yes)
			(layer "B.Fab")
			(hide yes)
			(effects
				(font
					(size 1.016 1.016)
					(thickness 0.1524)
				)
				(justify mirror)
			)
		)
		(property "Device Type" "C402H22"
			(at -1.1811 -4.2291 90)
			(unlocked yes)
			(layer "B.Fab")
			(hide yes)
			(effects
				(font
					(size 1.016 1.016)
					(thickness 0.1524)
				)
				(justify mirror)
			)
		)
		(duplicate_pad_numbers_are_jumpers no)
		(fp_rect
			(start 0.4318 0.9525)
			(end -0.4318 -0.9525)
			(stroke
				(width 0)
				(type default)
			)
			(fill no)
			(layer "B.CrtYd")
		)
		(fp_rect
			(start 0.4318 0.9525)
			(end -0.4318 -0.9525)
			(stroke
				(width 0)
				(type default)
			)
			(fill no)
			(layer "B.Fab")
		)
		(pad "1" smd custom
			(at 0 -0.4445 270)
			(size 0.1524 0.1524)
			(layers "B.Cu" "B.Mask" "B.Paste")
			(net "P0V9_E")
			(options
				(clearance outline)
				(anchor circle)
			)
			(primitives
				(gr_poly
					(pts
						(arc
							(start 0.3048 0.2032)
							(mid 0.275042 0.275042)
							(end 0.2032 0.3048)
						)
						(arc
							(start -0.2032 0.3048)
							(mid -0.275042 0.275042)
							(end -0.3048 0.2032)
						)
						(arc
							(start -0.3048 -0.2032)
							(mid -0.275042 -0.275042)
							(end -0.2032 -0.3048)
						)
						(arc
							(start 0.2032 -0.3048)
							(mid 0.275042 -0.275042)
							(end 0.3048 -0.2032)
						)
					)
					(width 0)
					(fill yes)
				)
			)
		)
		(pad "2" smd custom
			(at 0 0.4445 270)
			(size 0.1524 0.1524)
			(layers "B.Cu" "B.Mask" "B.Paste")
			(net "GND")
			(options
				(clearance outline)
				(anchor circle)
			)
			(primitives
				(gr_poly
					(pts
						(arc
							(start 0.3048 0.2032)
							(mid 0.275042 0.275042)
							(end 0.2032 0.3048)
						)
						(arc
							(start -0.2032 0.3048)
							(mid -0.275042 0.275042)
							(end -0.3048 0.2032)
						)
						(arc
							(start -0.3048 -0.2032)
							(mid -0.275042 -0.275042)
							(end -0.2032 -0.3048)
						)
						(arc
							(start 0.2032 -0.3048)
							(mid 0.275042 -0.275042)
							(end 0.3048 -0.2032)
						)
					)
					(width 0)
					(fill yes)
				)
			)
		)
	)
	(footprint ""
		(layer "B.Cu")
		(at 290.2966 -179.1462)
		(property "Reference" "TP151"
			(at 0 0 0)
			(layer "B.SilkS")
			(hide yes)
			(effects
				(font
					(size 1.27 1.27)
				)
				(justify mirror)
			)
		)
		(property "Value" "TPAD28"
			(at -0.0127 -1.8034 0)
			(unlocked yes)
			(layer "B.Fab")
			(hide yes)
			(effects
				(font
					(size 1.016 1.016)
					(thickness 0.1524)
				)
				(justify mirror)
			)
		)
		(property "Device Type" "TPAD28"
			(at -0.0127 -3.3274 0)
			(unlocked yes)
			(layer "B.Fab")
			(hide yes)
			(effects
				(font
					(size 1.016 1.016)
					(thickness 0.1524)
				)
				(justify mirror)
			)
		)
		(duplicate_pad_numbers_are_jumpers no)
		(fp_poly
			(pts
				(arc
					(start 0.3556 0)
					(mid -0.3556 0)
					(end 0.3556 0)
				)
			)
			(stroke
				(width 0)
				(type default)
			)
			(fill no)
			(layer "B.CrtYd")
		)
		(fp_poly
			(pts
				(arc
					(start 0.6096 0)
					(mid -0.6096 0)
					(end 0.6096 0)
				)
			)
			(stroke
				(width 0)
				(type default)
			)
			(fill no)
			(layer "B.Fab")
		)
		(pad "1" smd circle
			(at 0 0 180)
			(size 0.7112 0.7112)
			(layers "B.Cu" "B.Mask" "B.Paste")
			(net "TP_BMC_GPIOR3")
		)
	)
	(footprint ""
		(layer "B.Cu")
		(at 274.193 -178.689 90)
		(property "Reference" "R356"
			(at 0 0 90)
			(layer "B.SilkS")
			(hide yes)
			(effects
				(font
					(size 1.27 1.27)
				)
				(justify mirror)
			)
		)
		(property "Value" "3K3R2F-2-GP"
			(at -0.064008 -3.993896 90)
			(unlocked yes)
			(layer "B.Fab")
			(hide yes)
			(effects
				(font
					(size 1.016 1.016)
					(thickness 0.1524)
				)
				(justify mirror)
			)
		)
		(property "Device Type" "R402H16"
			(at -0.064008 -5.517896 90)
			(unlocked yes)
			(layer "B.Fab")
			(hide yes)
			(effects
				(font
					(size 1.016 1.016)
					(thickness 0.1524)
				)
				(justify mirror)
			)
		)
		(duplicate_pad_numbers_are_jumpers no)
		(fp_line
			(start 0.508 -0.9398)
			(end 0.508 0.9398)
			(stroke
				(width 0.1524)
				(type default)
			)
			(layer "B.SilkS")
		)
		(fp_line
			(start -0.508 -0.9398)
			(end 0.508 -0.9398)
			(stroke
				(width 0.1524)
				(type default)
			)
			(layer "B.SilkS")
		)
		(fp_rect
			(start 0.508 0.9398)
			(end -0.508 -0.9398)
			(stroke
				(width 0)
				(type default)
			)
			(fill no)
			(layer "B.CrtYd")
		)
		(fp_rect
			(start 0.508 0.9398)
			(end -0.508 -0.9398)
			(stroke
				(width 0)
				(type default)
			)
			(fill no)
			(layer "B.Fab")
		)
		(pad "1" smd custom
			(at 0 -0.4445 270)
			(size 0.1397 0.1397)
			(layers "B.Cu" "B.Mask" "B.Paste")
			(net "P3V3_STBY")
			(options
				(clearance outline)
				(anchor circle)
			)
			(primitives
				(gr_poly
					(pts
						(arc
							(start -0.1778 0.2794)
							(mid -0.249642 0.249642)
							(end -0.2794 0.1778)
						)
						(arc
							(start -0.2794 -0.1778)
							(mid -0.249642 -0.249642)
							(end -0.1778 -0.2794)
						)
						(arc
							(start 0.1778 -0.2794)
							(mid 0.249642 -0.249642)
							(end 0.2794 -0.1778)
						)
						(arc
							(start 0.2794 0.1778)
							(mid 0.249642 0.249642)
							(end 0.1778 0.2794)
						)
					)
					(width 0)
					(fill yes)
				)
			)
		)
		(pad "2" smd custom
			(at 0 0.4445 270)
			(size 0.1397 0.1397)
			(layers "B.Cu" "B.Mask" "B.Paste")
			(net "ROMA12")
			(options
				(clearance outline)
				(anchor circle)
			)
			(primitives
				(gr_poly
					(pts
						(arc
							(start -0.1778 0.2794)
							(mid -0.249642 0.249642)
							(end -0.2794 0.1778)
						)
						(arc
							(start -0.2794 -0.1778)
							(mid -0.249642 -0.249642)
							(end -0.1778 -0.2794)
						)
						(arc
							(start 0.1778 -0.2794)
							(mid 0.249642 -0.249642)
							(end 0.2794 -0.1778)
						)
						(arc
							(start 0.2794 0.1778)
							(mid 0.249642 0.249642)
							(end 0.1778 0.2794)
						)
					)
					(width 0)
					(fill yes)
				)
			)
		)
	)
	(footprint ""
		(layer "B.Cu")
		(at 95.155766 -43.7388 180)
		(property "Reference" "SC963"
			(at 0 0 0)
			(layer "B.SilkS")
			(hide yes)
			(effects
				(font
					(size 1.27 1.27)
				)
				(justify mirror)
			)
		)
		(property "Value" "SCD1U6D3V1KX-GP"
			(at 2.8321 -1.7399 180)
			(unlocked yes)
			(layer "B.Fab")
			(hide yes)
			(effects
				(font
					(size 1.016 1.016)
					(thickness 0.1524)
				)
				(justify mirror)
			)
		)
		(property "Device Type" "C0201H13"
			(at 2.8321 -3.2639 180)
			(unlocked yes)
			(layer "B.Fab")
			(hide yes)
			(effects
				(font
					(size 1.016 1.016)
					(thickness 0.1524)
				)
				(justify mirror)
			)
		)
		(duplicate_pad_numbers_are_jumpers no)
		(fp_rect
			(start 0.2794 0.6477)
			(end -0.2794 -0.6477)
			(stroke
				(width 0)
				(type default)
			)
			(fill no)
			(layer "B.CrtYd")
		)
		(fp_rect
			(start 0.2794 0.6477)
			(end -0.2794 -0.6477)
			(stroke
				(width 0)
				(type default)
			)
			(fill no)
			(layer "B.Fab")
		)
		(pad "1" smd custom
			(at 0 -0.2794)
			(size 0.0762 0.0762)
			(layers "B.Cu" "B.Mask" "B.Paste")
			(net "SAS0_AVDD")
			(options
				(clearance outline)
				(anchor circle)
			)
			(primitives
				(gr_poly
					(pts
						(arc
							(start 0.1524 0.127)
							(mid 0.137521 0.162921)
							(end 0.1016 0.1778)
						)
						(arc
							(start -0.1016 0.1778)
							(mid -0.137521 0.162921)
							(end -0.1524 0.127)
						)
						(arc
							(start -0.1524 -0.127)
							(mid -0.137521 -0.162921)
							(end -0.1016 -0.1778)
						)
						(arc
							(start 0.1016 -0.1778)
							(mid 0.137521 -0.162921)
							(end 0.1524 -0.127)
						)
					)
					(width 0)
					(fill yes)
				)
			)
		)
		(pad "2" smd custom
			(at 0 0.2794)
			(size 0.0762 0.0762)
			(layers "B.Cu" "B.Mask" "B.Paste")
			(net "GND")
			(options
				(clearance outline)
				(anchor circle)
			)
			(primitives
				(gr_poly
					(pts
						(arc
							(start 0.1524 0.127)
							(mid 0.137521 0.162921)
							(end 0.1016 0.1778)
						)
						(arc
							(start -0.1016 0.1778)
							(mid -0.137521 0.162921)
							(end -0.1524 0.127)
						)
						(arc
							(start -0.1524 -0.127)
							(mid -0.137521 -0.162921)
							(end -0.1016 -0.1778)
						)
						(arc
							(start 0.1016 -0.1778)
							(mid 0.137521 -0.162921)
							(end 0.1524 -0.127)
						)
					)
					(width 0)
					(fill yes)
				)
			)
		)
	)
	(footprint ""
		(layer "B.Cu")
		(at 256.667 -19.431)
		(property "Reference" "R407"
			(at 0 0 0)
			(layer "B.SilkS")
			(hide yes)
			(effects
				(font
					(size 1.27 1.27)
				)
				(justify mirror)
			)
		)
		(property "Value" "10KR2F-2-GP"
			(at -0.064008 -3.993896 0)
			(unlocked yes)
			(layer "B.Fab")
			(hide yes)
			(effects
				(font
					(size 1.016 1.016)
					(thickness 0.1524)
				)
				(justify mirror)
			)
		)
		(property "Device Type" "R402H16"
			(at -0.064008 -5.517896 0)
			(unlocked yes)
			(layer "B.Fab")
			(hide yes)
			(effects
				(font
					(size 1.016 1.016)
					(thickness 0.1524)
				)
				(justify mirror)
			)
		)
		(duplicate_pad_numbers_are_jumpers no)
		(fp_line
			(start -0.508 -0.9398)
			(end 0.508 -0.9398)
			(stroke
				(width 0.1524)
				(type default)
			)
			(layer "B.SilkS")
		)
		(fp_line
			(start 0.508 -0.9398)
			(end 0.508 0.9398)
			(stroke
				(width 0.1524)
				(type default)
			)
			(layer "B.SilkS")
		)
		(fp_rect
			(start 0.508 0.9398)
			(end -0.508 -0.9398)
			(stroke
				(width 0)
				(type default)
			)
			(fill no)
			(layer "B.CrtYd")
		)
		(fp_rect
			(start 0.508 0.9398)
			(end -0.508 -0.9398)
			(stroke
				(width 0)
				(type default)
			)
			(fill no)
			(layer "B.Fab")
		)
		(pad "1" smd custom
			(at 0 -0.4445 180)
			(size 0.1397 0.1397)
			(layers "B.Cu" "B.Mask" "B.Paste")
			(net "P5V_STBY")
			(options
				(clearance outline)
				(anchor circle)
			)
			(primitives
				(gr_poly
					(pts
						(arc
							(start -0.1778 0.2794)
							(mid -0.249642 0.249642)
							(end -0.2794 0.1778)
						)
						(arc
							(start -0.2794 -0.1778)
							(mid -0.249642 -0.249642)
							(end -0.1778 -0.2794)
						)
						(arc
							(start 0.1778 -0.2794)
							(mid 0.249642 -0.249642)
							(end 0.2794 -0.1778)
						)
						(arc
							(start 0.2794 0.1778)
							(mid 0.249642 0.249642)
							(end 0.1778 0.2794)
						)
					)
					(width 0)
					(fill yes)
				)
			)
		)
		(pad "2" smd custom
			(at 0 0.4445 180)
			(size 0.1397 0.1397)
			(layers "B.Cu" "B.Mask" "B.Paste")
			(net "USB_OCS_N1")
			(options
				(clearance outline)
				(anchor circle)
			)
			(primitives
				(gr_poly
					(pts
						(arc
							(start -0.1778 0.2794)
							(mid -0.249642 0.249642)
							(end -0.2794 0.1778)
						)
						(arc
							(start -0.2794 -0.1778)
							(mid -0.249642 -0.249642)
							(end -0.1778 -0.2794)
						)
						(arc
							(start 0.1778 -0.2794)
							(mid 0.249642 -0.249642)
							(end 0.2794 -0.1778)
						)
						(arc
							(start 0.2794 0.1778)
							(mid 0.249642 0.249642)
							(end 0.1778 0.2794)
						)
					)
					(width 0)
					(fill yes)
				)
			)
		)
	)
	(footprint ""
		(layer "B.Cu")
		(at 307.594 -180.086)
		(property "Reference" "L4"
			(at 0 0 0)
			(layer "B.SilkS")
			(hide yes)
			(effects
				(font
					(size 1.27 1.27)
				)
				(justify mirror)
			)
		)
		(property "Value" "MMZ2012S601ATA1N-GP"
			(at 0 -4.2418 0)
			(unlocked yes)
			(layer "B.Fab")
			(hide yes)
			(effects
				(font
					(size 1.016 1.016)
					(thickness 0.1524)
				)
				(justify mirror)
			)
		)
		(property "Device Type" "L805H42"
			(at 0 -5.7912 0)
			(unlocked yes)
			(layer "B.Fab")
			(hide yes)
			(effects
				(font
					(size 1.016 1.016)
					(thickness 0.1524)
				)
				(justify mirror)
			)
		)
		(duplicate_pad_numbers_are_jumpers no)
		(fp_line
			(start -0.889 -1.7018)
			(end -0.889 1.7018)
			(stroke
				(width 0.1524)
				(type default)
			)
			(layer "B.SilkS")
		)
		(fp_line
			(start -0.889 1.7018)
			(end 0.889 1.7018)
			(stroke
				(width 0.1524)
				(type default)
			)
			(layer "B.SilkS")
		)
		(fp_line
			(start 0.889 -1.7018)
			(end -0.889 -1.7018)
			(stroke
				(width 0.1524)
				(type default)
			)
			(layer "B.SilkS")
		)
		(fp_line
			(start 0.889 1.7018)
			(end 0.889 -1.7018)
			(stroke
				(width 0.1524)
				(type default)
			)
			(layer "B.SilkS")
		)
		(fp_rect
			(start 0.9652 1.778)
			(end -0.9652 -1.778)
			(stroke
				(width 0)
				(type default)
			)
			(fill no)
			(layer "B.CrtYd")
		)
		(fp_rect
			(start 0.9652 1.778)
			(end -0.9652 -1.778)
			(stroke
				(width 0)
				(type default)
			)
			(fill no)
			(layer "B.Fab")
		)
		(pad "1" smd rect
			(at 0 -0.9652 180)
			(size 1.397 1.143)
			(layers "B.Cu" "B.Mask" "B.Paste")
			(net "P3V3_STBY")
		)
		(pad "2" smd rect
			(at 0 0.9652 180)
			(size 1.397 1.143)
			(layers "B.Cu" "B.Mask" "B.Paste")
			(net "ADCAV33")
		)
	)
	(footprint ""
		(layer "B.Cu")
		(at 296.48912 -170.7007)
		(property "Reference" "TP93"
			(at 0 0 0)
			(layer "B.SilkS")
			(hide yes)
			(effects
				(font
					(size 1.27 1.27)
				)
				(justify mirror)
			)
		)
		(property "Value" "TPAD28"
			(at -0.0127 -1.8034 0)
			(unlocked yes)
			(layer "B.Fab")
			(hide yes)
			(effects
				(font
					(size 1.016 1.016)
					(thickness 0.1524)
				)
				(justify mirror)
			)
		)
		(property "Device Type" "TPAD28"
			(at -0.0127 -3.3274 0)
			(unlocked yes)
			(layer "B.Fab")
			(hide yes)
			(effects
				(font
					(size 1.016 1.016)
					(thickness 0.1524)
				)
				(justify mirror)
			)
		)
		(duplicate_pad_numbers_are_jumpers no)
		(fp_poly
			(pts
				(arc
					(start 0.3556 0)
					(mid -0.3556 0)
					(end 0.3556 0)
				)
			)
			(stroke
				(width 0)
				(type default)
			)
			(fill no)
			(layer "B.CrtYd")
		)
		(fp_poly
			(pts
				(arc
					(start 0.6096 0)
					(mid -0.6096 0)
					(end 0.6096 0)
				)
			)
			(stroke
				(width 0)
				(type default)
			)
			(fill no)
			(layer "B.Fab")
		)
		(pad "1" smd circle
			(at 0 0 180)
			(size 0.7112 0.7112)
			(layers "B.Cu" "B.Mask" "B.Paste")
			(net "TP_GPIOH4")
		)
	)
	(footprint ""
		(layer "B.Cu")
		(at 108.020612 -218.44 -90)
		(property "Reference" "SR912"
			(at 0 0 90)
			(layer "B.SilkS")
			(hide yes)
			(effects
				(font
					(size 1.27 1.27)
				)
				(justify mirror)
			)
		)
		(property "Value" "4K7R2F-GP"
			(at -0.064008 -3.993896 270)
			(unlocked yes)
			(layer "B.Fab")
			(hide yes)
			(effects
				(font
					(size 1.016 1.016)
					(thickness 0.1524)
				)
				(justify mirror)
			)
		)
		(property "Device Type" "R402H16"
			(at -0.064008 -5.517896 270)
			(unlocked yes)
			(layer "B.Fab")
			(hide yes)
			(effects
				(font
					(size 1.016 1.016)
					(thickness 0.1524)
				)
				(justify mirror)
			)
		)
		(duplicate_pad_numbers_are_jumpers no)
		(fp_line
			(start -0.508 -0.9398)
			(end 0.508 -0.9398)
			(stroke
				(width 0.1524)
				(type default)
			)
			(layer "B.SilkS")
		)
		(fp_line
			(start 0.508 -0.9398)
			(end 0.508 0.9398)
			(stroke
				(width 0.1524)
				(type default)
			)
			(layer "B.SilkS")
		)
		(fp_rect
			(start 0.508 0.9398)
			(end -0.508 -0.9398)
			(stroke
				(width 0)
				(type default)
			)
			(fill no)
			(layer "B.CrtYd")
		)
		(fp_rect
			(start 0.508 0.9398)
			(end -0.508 -0.9398)
			(stroke
				(width 0)
				(type default)
			)
			(fill no)
			(layer "B.Fab")
		)
		(pad "1" smd custom
			(at 0 -0.4445 90)
			(size 0.1397 0.1397)
			(layers "B.Cu" "B.Mask" "B.Paste")
			(net "REDV_I2C_SEL1B")
			(options
				(clearance outline)
				(anchor circle)
			)
			(primitives
				(gr_poly
					(pts
						(arc
							(start -0.1778 0.2794)
							(mid -0.249642 0.249642)
							(end -0.2794 0.1778)
						)
						(arc
							(start -0.2794 -0.1778)
							(mid -0.249642 -0.249642)
							(end -0.1778 -0.2794)
						)
						(arc
							(start 0.1778 -0.2794)
							(mid 0.249642 -0.249642)
							(end 0.2794 -0.1778)
						)
						(arc
							(start 0.2794 0.1778)
							(mid 0.249642 0.249642)
							(end 0.1778 0.2794)
						)
					)
					(width 0)
					(fill yes)
				)
			)
		)
		(pad "2" smd custom
			(at 0 0.4445 90)
			(size 0.1397 0.1397)
			(layers "B.Cu" "B.Mask" "B.Paste")
			(net "GND")
			(options
				(clearance outline)
				(anchor circle)
			)
			(primitives
				(gr_poly
					(pts
						(arc
							(start -0.1778 0.2794)
							(mid -0.249642 0.249642)
							(end -0.2794 0.1778)
						)
						(arc
							(start -0.2794 -0.1778)
							(mid -0.249642 -0.249642)
							(end -0.1778 -0.2794)
						)
						(arc
							(start 0.1778 -0.2794)
							(mid 0.249642 -0.249642)
							(end 0.2794 -0.1778)
						)
						(arc
							(start 0.2794 0.1778)
							(mid 0.249642 0.249642)
							(end 0.1778 0.2794)
						)
					)
					(width 0)
					(fill yes)
				)
			)
		)
	)
)
